# BASEBOARD_FAB2 (Tioga Pass) — schematic netlist excerpt (pin names and nets, part order shuffled) for the footprints in the layout excerpt that follows; sources: Cadence DE-HDL packaged netlist, KiCad conversion of Wiwynn_Tioga_Pass_MB.brd

C5P15  CAP  47UF 4V 20% X6S  pkg 0805  page 42 : A = PVCCIN_CPU0 ; B = GND
R7G27  RES  1.00K 1% CHIP  pkg 0402  page 136 : A = P3V3_STBY ; B = PU_BIOS_USB_RECOVERY
R2P13  RES  4.75K 1% CHIP  pkg 0402  page 170 : A = P3V3_STBY ; B = FM_PMBUS_ALERT_BUF_EN_N

(kicad_pcb
	(version 20260206)
	(generator "pcbnew")
	(generator_version "10.0")
	(general
		(thickness 1.6)
		(legacy_teardrops no)
	)
	(paper "A4")
	(title_block
		(title "Wiwynn_Tioga_Pass_MB.brd")
		(comment 1 "Tioga Pass / footprints 4122-4124 of 4770")
	)
	(layers
		(0 "F.Cu" signal "TOP")
		(4 "In1.Cu" signal "L2GND")
		(6 "In2.Cu" signal "L3")
		(8 "In3.Cu" signal "L4GND")
		(10 "In4.Cu" signal "L5")
		(12 "In5.Cu" signal "L6GND")
		(14 "In6.Cu" signal "L7VCC")
		(16 "In7.Cu" signal "L8VCC")
		(18 "In8.Cu" signal "L9GND")
		(20 "In9.Cu" signal "L10")
		(22 "In10.Cu" signal "L11GND")
		(24 "In11.Cu" signal "L12")
		(26 "In12.Cu" signal "L13GND")
		(2 "B.Cu" signal "BOTTOM")
		(9 "F.Adhes" user "F.Adhesive")
		(11 "B.Adhes" user "B.Adhesive")
		(13 "F.Paste" user "Package Geometry/Pastemask Top")
		(15 "B.Paste" user "Package Geometry/Pastemask Bottom")
		(5 "F.SilkS" user "Ref Des/Silkscreen Top")
		(7 "B.SilkS" user "Ref Des/Silkscreen Bottom")
		(1 "F.Mask" user "Board Geometry/Soldermask Top")
		(3 "B.Mask" user "Board Geometry/Soldermask Bottom")
		(17 "Dwgs.User" user "User.Drawings")
		(19 "Cmts.User" user "User.Comments")
		(21 "Eco1.User" user "User.Eco1")
		(23 "Eco2.User" user "User.Eco2")
		(25 "Edge.Cuts" user "Board Geometry/Outline")
		(27 "Margin" user)
		(31 "F.CrtYd" user "Package Geometry/Place Bound Top")
		(29 "B.CrtYd" user "Package Geometry/Place Bound Bottom")
		(35 "F.Fab" user "Ref Des/Assembly Top")
		(33 "B.Fab" user "Ref Des/Assembly Bottom")
	)
	(footprint ""
		(layer "B.Cu")
		(at 266.245086 -79.60614 180)
		(property "Reference" "C5P15"
			(at 0 0 0)
			(layer "B.SilkS")
			(hide yes)
			(effects
				(font
					(size 1.27 1.27)
				)
				(justify mirror)
			)
		)
		(property "Value" ""
			(at 0 0 0)
			(layer "B.Fab")
			(effects
				(font
					(size 1.27 1.27)
				)
				(justify mirror)
			)
		)
		(duplicate_pad_numbers_are_jumpers no)
		(fp_poly
			(pts
				(xy 0.7239 -0.2159) (xy -0.7239 -0.2159) (xy -0.7239 1.9939) (xy 0.7239 1.9939)
			)
			(stroke
				(width 0)
				(type default)
			)
			(fill no)
			(layer "B.CrtYd")
		)
		(fp_line
			(start 0.7239 1.9939)
			(end -0.7239 1.9939)
			(stroke
				(width 0.1)
				(type default)
			)
			(layer "B.Fab")
		)
		(fp_line
			(start 0.7239 -0.2159)
			(end 0.7239 1.9939)
			(stroke
				(width 0.1)
				(type default)
			)
			(layer "B.Fab")
		)
		(fp_line
			(start -0.7239 1.9939)
			(end -0.7239 -0.2159)
			(stroke
				(width 0.1)
				(type default)
			)
			(layer "B.Fab")
		)
		(fp_line
			(start -0.7239 -0.2159)
			(end 0.7239 -0.2159)
			(stroke
				(width 0.1)
				(type default)
			)
			(layer "B.Fab")
		)
		(pad "1" smd rect
			(at 0 0)
			(size 1.27 1.016)
			(layers "B.Cu" "B.Mask" "B.Paste")
			(net "PVCCIN_CPU0")
		)
		(pad "2" smd rect
			(at 0 1.778)
			(size 1.27 1.016)
			(layers "B.Cu" "B.Mask" "B.Paste")
			(net "GND")
		)
		(zone
			(layer "B.Cu")
			(hatch none 0.5)
			(connect_pads
				(clearance 0)
			)
			(min_thickness 0.25)
			(keepout
				(tracks not_allowed)
				(vias allowed)
				(pads allowed)
				(copperpour not_allowed)
				(footprints allowed)
			)
			(placement
				(enabled no)
				(sheetname "")
			)
			(fill
				(thermal_gap 0.5)
				(thermal_bridge_width 0.5)
				(island_removal_mode 0)
			)
			(polygon
				(pts
					(xy 265.610086 -80.11414) (xy 266.880086 -80.11414) (xy 266.880086 -80.87614) (xy 265.610086 -80.87614)
				)
			)
		)
	)
	(footprint ""
		(layer "B.Cu")
		(at 372.872 -6.1595)
		(property "Reference" "R7G27"
			(at 0 0 0)
			(layer "B.SilkS")
			(hide yes)
			(effects
				(font
					(size 1.27 1.27)
				)
				(justify mirror)
			)
		)
		(property "Value" ""
			(at 0 0 0)
			(layer "B.Fab")
			(effects
				(font
					(size 1.27 1.27)
				)
				(justify mirror)
			)
		)
		(duplicate_pad_numbers_are_jumpers no)
		(fp_poly
			(pts
				(xy 0.2794 -0.1016) (xy -0.2794 -0.1016) (xy -0.2794 0.9906) (xy 0.2794 0.9906)
			)
			(stroke
				(width 0)
				(type default)
			)
			(fill no)
			(layer "B.CrtYd")
		)
		(fp_line
			(start -0.2794 -0.1016)
			(end 0.2794 -0.1016)
			(stroke
				(width 0.1)
				(type default)
			)
			(layer "B.Fab")
		)
		(fp_line
			(start -0.2794 0.9906)
			(end -0.2794 -0.1016)
			(stroke
				(width 0.1)
				(type default)
			)
			(layer "B.Fab")
		)
		(fp_line
			(start 0.2794 -0.1016)
			(end 0.2794 0.9906)
			(stroke
				(width 0.1)
				(type default)
			)
			(layer "B.Fab")
		)
		(fp_line
			(start 0.2794 0.9906)
			(end -0.2794 0.9906)
			(stroke
				(width 0.1)
				(type default)
			)
			(layer "B.Fab")
		)
		(pad "1" smd rect
			(at 0 0 180)
			(size 0.508 0.508)
			(layers "B.Cu" "B.Mask" "B.Paste")
			(net "P3V3_STBY")
		)
		(pad "2" smd rect
			(at 0 0.889 180)
			(size 0.508 0.508)
			(layers "B.Cu" "B.Mask" "B.Paste")
			(net "PU_BIOS_USB_RECOVERY")
		)
		(zone
			(layer "B.Cu")
			(hatch none 0.5)
			(connect_pads
				(clearance 0)
			)
			(min_thickness 0.25)
			(keepout
				(tracks allowed)
				(vias not_allowed)
				(pads allowed)
				(copperpour not_allowed)
				(footprints allowed)
			)
			(placement
				(enabled no)
				(sheetname "")
			)
			(fill
				(thermal_gap 0.5)
				(thermal_bridge_width 0.5)
				(island_removal_mode 0)
			)
			(polygon
				(pts
					(xy 373.126 -5.9055) (xy 372.618 -5.9055) (xy 372.618 -5.5245) (xy 373.126 -5.5245)
				)
			)
		)
		(zone
			(layer "B.Cu")
			(hatch none 0.5)
			(connect_pads
				(clearance 0)
			)
			(min_thickness 0.25)
			(keepout
				(tracks not_allowed)
				(vias allowed)
				(pads allowed)
				(copperpour not_allowed)
				(footprints allowed)
			)
			(placement
				(enabled no)
				(sheetname "")
			)
			(fill
				(thermal_gap 0.5)
				(thermal_bridge_width 0.5)
				(island_removal_mode 0)
			)
			(polygon
				(pts
					(xy 373.126 -5.5245) (xy 372.618 -5.5245) (xy 372.618 -5.9055) (xy 373.126 -5.9055)
				)
			)
		)
	)
	(footprint ""
		(layer "B.Cu")
		(at 421.513 -81.4705)
		(property "Reference" "R2P13"
			(at 0 0 0)
			(layer "B.SilkS")
			(hide yes)
			(effects
				(font
					(size 1.27 1.27)
				)
				(justify mirror)
			)
		)
		(property "Value" ""
			(at 0 0 0)
			(layer "B.Fab")
			(effects
				(font
					(size 1.27 1.27)
				)
				(justify mirror)
			)
		)
		(duplicate_pad_numbers_are_jumpers no)
		(fp_poly
			(pts
				(xy 0.2794 -0.1016) (xy -0.2794 -0.1016) (xy -0.2794 0.9906) (xy 0.2794 0.9906)
			)
			(stroke
				(width 0)
				(type default)
			)
			(fill no)
			(layer "B.CrtYd")
		)
		(fp_line
			(start -0.2794 -0.1016)
			(end 0.2794 -0.1016)
			(stroke
				(width 0.1)
				(type default)
			)
			(layer "B.Fab")
		)
		(fp_line
			(start -0.2794 0.9906)
			(end -0.2794 -0.1016)
			(stroke
				(width 0.1)
				(type default)
			)
			(layer "B.Fab")
		)
		(fp_line
			(start 0.2794 -0.1016)
			(end 0.2794 0.9906)
			(stroke
				(width 0.1)
				(type default)
			)
			(layer "B.Fab")
		)
		(fp_line
			(start 0.2794 0.9906)
			(end -0.2794 0.9906)
			(stroke
				(width 0.1)
				(type default)
			)
			(layer "B.Fab")
		)
		(pad "1" smd rect
			(at 0 0 180)
			(size 0.508 0.508)
			(layers "B.Cu" "B.Mask" "B.Paste")
			(net "P3V3_STBY")
		)
		(pad "2" smd rect
			(at 0 0.889 180)
			(size 0.508 0.508)
			(layers "B.Cu" "B.Mask" "B.Paste")
			(net "FM_PMBUS_ALERT_BUF_EN_N")
		)
		(zone
			(layer "B.Cu")
			(hatch none 0.5)
			(connect_pads
				(clearance 0)
			)
			(min_thickness 0.25)
			(keepout
				(tracks allowed)
				(vias not_allowed)
				(pads allowed)
				(copperpour not_allowed)
				(footprints allowed)
			)
			(placement
				(enabled no)
				(sheetname "")
			)
			(fill
				(thermal_gap 0.5)
				(thermal_bridge_width 0.5)
				(island_removal_mode 0)
			)
			(polygon
				(pts
					(xy 421.767 -81.2165) (xy 421.259 -81.2165) (xy 421.259 -80.8355) (xy 421.767 -80.8355)
				)
			)
		)
		(zone
			(layer "B.Cu")
			(hatch none 0.5)
			(connect_pads
				(clearance 0)
			)
			(min_thickness 0.25)
			(keepout
				(tracks not_allowed)
				(vias allowed)
				(pads allowed)
				(copperpour not_allowed)
				(footprints allowed)
			)
			(placement
				(enabled no)
				(sheetname "")
			)
			(fill
				(thermal_gap 0.5)
				(thermal_bridge_width 0.5)
				(island_removal_mode 0)
			)
			(polygon
				(pts
					(xy 421.767 -80.8355) (xy 421.259 -80.8355) (xy 421.259 -81.2165) (xy 421.767 -81.2165)
				)
			)
		)
	)
)
